(kicad_pcb
	(version 20260206)
	(generator "pcbnew")
	(generator_version "10.0")
	(general
		(thickness 1.6)
		(legacy_teardrops no)
	)
	(paper "A4")
	(title_block
		(title "01162023_DA0F0TEBIF0_F0T_Expander_BD_F_brd_V02_OCP.brd")
		(comment 1 "Grand Teton / footprints 2401-2407 of 9728")
	)
	(layers
		(0 "F.Cu" signal "TOP")
		(4 "In1.Cu" signal "GND")
		(6 "In2.Cu" signal "VCC")
		(8 "In3.Cu" signal "VCC1")
		(10 "In4.Cu" signal "GND1")
		(12 "In5.Cu" signal "IN1")
		(14 "In6.Cu" signal "GND2")
		(16 "In7.Cu" signal "IN2")
		(18 "In8.Cu" signal "GND3")
		(20 "In9.Cu" signal "IN3")
		(22 "In10.Cu" signal "GND4")
		(24 "In11.Cu" signal "IN4")
		(26 "In12.Cu" signal "GND5")
		(28 "In13.Cu" signal "IN5")
		(30 "In14.Cu" signal "GND6")
		(32 "In15.Cu" signal "IN6")
		(34 "In16.Cu" signal "GND7")
		(2 "B.Cu" signal "BOTTOM")
		(9 "F.Adhes" user "F.Adhesive")
		(11 "B.Adhes" user "B.Adhesive")
		(13 "F.Paste" user "Package Geometry/Pastemask Top")
		(15 "B.Paste" user "Package Geometry/Pastemask Bottom")
		(5 "F.SilkS" user "Ref Des/Silkscreen Top")
		(7 "B.SilkS" user "Ref Des/Silkscreen Bottom")
		(1 "F.Mask" user "Board Geometry/Soldermask Top")
		(3 "B.Mask" user "Board Geometry/Soldermask Bottom")
		(17 "Dwgs.User" user "User.Drawings")
		(19 "Cmts.User" user "User.Comments")
		(21 "Eco1.User" user "User.Eco1")
		(23 "Eco2.User" user "User.Eco2")
		(25 "Edge.Cuts" user "Board Geometry/Outline")
		(27 "Margin" user)
		(31 "F.CrtYd" user "Package Geometry/Place Bound Top")
		(29 "B.CrtYd" user "Package Geometry/Place Bound Bottom")
		(35 "F.Fab" user "Ref Des/Assembly Top")
		(33 "B.Fab" user "Ref Des/Assembly Bottom")
	)
	(footprint ""
		(layer "F.Cu")
		(at 410.932122 -169.040302 -90)
		(property "Reference" "U42"
			(at 0.333502 2.295652 90)
			(unlocked yes)
			(layer "F.SilkS")
			(effects
				(font
					(size 0.7874 0.5842)
					(thickness 0.1524)
				)
			)
		)
		(property "Value" ""
			(at 0 0 270)
			(layer "F.Fab")
			(effects
				(font
					(size 1.27 1.27)
				)
			)
		)
		(duplicate_pad_numbers_are_jumpers no)
		(fp_line
			(start -1.905 1.651)
			(end -1.905 -1.651)
			(stroke
				(width 0.1524)
				(type default)
			)
			(layer "F.SilkS")
		)
		(fp_line
			(start 1.905 1.651)
			(end -1.905 1.651)
			(stroke
				(width 0.1524)
				(type default)
			)
			(layer "F.SilkS")
		)
		(fp_line
			(start -1.905 -1.651)
			(end 1.905 -1.651)
			(stroke
				(width 0.1524)
				(type default)
			)
			(layer "F.SilkS")
		)
		(fp_line
			(start 1.905 -1.651)
			(end 1.905 1.651)
			(stroke
				(width 0.1524)
				(type default)
			)
			(layer "F.SilkS")
		)
		(fp_line
			(start -0.649986 1.524)
			(end -0.649986 1.169924)
			(stroke
				(width 0.1)
				(type default)
			)
			(layer "F.Fab")
		)
		(fp_line
			(start 0.6985 1.524)
			(end -0.649986 1.524)
			(stroke
				(width 0.1)
				(type default)
			)
			(layer "F.Fab")
		)
		(fp_line
			(start -1.249934 1.169924)
			(end -1.249934 0.729996)
			(stroke
				(width 0.1)
				(type default)
			)
			(layer "F.Fab")
		)
		(fp_line
			(start -0.649986 1.169924)
			(end -1.249934 1.169924)
			(stroke
				(width 0.1)
				(type default)
			)
			(layer "F.Fab")
		)
		(fp_line
			(start -1.249934 0.729996)
			(end -0.6985 0.729996)
			(stroke
				(width 0.1)
				(type default)
			)
			(layer "F.Fab")
		)
		(fp_line
			(start -0.6985 0.729996)
			(end -0.6985 -0.729996)
			(stroke
				(width 0.1)
				(type default)
			)
			(layer "F.Fab")
		)
		(fp_line
			(start 0.6985 0.219964)
			(end 0.6985 1.524)
			(stroke
				(width 0.1)
				(type default)
			)
			(layer "F.Fab")
		)
		(fp_line
			(start 1.249934 0.219964)
			(end 0.6985 0.219964)
			(stroke
				(width 0.1)
				(type default)
			)
			(layer "F.Fab")
		)
		(fp_line
			(start 0.6985 -0.219964)
			(end 1.249934 -0.219964)
			(stroke
				(width 0.1)
				(type default)
			)
			(layer "F.Fab")
		)
		(fp_line
			(start 1.249934 -0.219964)
			(end 1.249934 0.219964)
			(stroke
				(width 0.1)
				(type default)
			)
			(layer "F.Fab")
		)
		(fp_line
			(start -1.249934 -0.729996)
			(end -1.249934 -1.169924)
			(stroke
				(width 0.1)
				(type default)
			)
			(layer "F.Fab")
		)
		(fp_line
			(start -0.6985 -0.729996)
			(end -1.249934 -0.729996)
			(stroke
				(width 0.1)
				(type default)
			)
			(layer "F.Fab")
		)
		(fp_line
			(start -1.249934 -1.169924)
			(end -0.649986 -1.169924)
			(stroke
				(width 0.1)
				(type default)
			)
			(layer "F.Fab")
		)
		(fp_line
			(start -0.649986 -1.169924)
			(end -0.649986 -1.524)
			(stroke
				(width 0.1)
				(type default)
			)
			(layer "F.Fab")
		)
		(fp_line
			(start -0.649986 -1.524)
			(end 0.6985 -1.524)
			(stroke
				(width 0.1)
				(type default)
			)
			(layer "F.Fab")
		)
		(fp_line
			(start 0.6985 -1.524)
			(end 0.6985 -0.219964)
			(stroke
				(width 0.1)
				(type default)
			)
			(layer "F.Fab")
		)
		(pad "1" smd rect
			(at -1.1176 -1.016 180)
			(size 1.016 1.27)
			(layers "F.Cu" "F.Mask" "F.Paste")
			(net "HP_NIC6_PWRGD")
		)
		(pad "2" smd rect
			(at -1.1176 1.016 180)
			(size 1.016 1.27)
			(layers "F.Cu" "F.Mask" "F.Paste")
			(net "P3V3_NIC6")
		)
		(pad "3" smd rect
			(at 1.1176 0 180)
			(size 1.016 1.27)
			(layers "F.Cu" "F.Mask" "F.Paste")
			(net "GND")
		)
	)
	(footprint ""
		(layer "F.Cu")
		(at 144.975326 -63.086234)
		(property "Reference" "R5979"
			(at 0 0 0)
			(layer "F.SilkS")
			(hide yes)
			(effects
				(font
					(size 1.27 1.27)
				)
			)
		)
		(property "Value" ""
			(at 0 0 0)
			(layer "F.Fab")
			(effects
				(font
					(size 1.27 1.27)
				)
			)
		)
		(duplicate_pad_numbers_are_jumpers no)
		(fp_line
			(start -0.7874 -0.4064)
			(end 0.7874 -0.4064)
			(stroke
				(width 0.1524)
				(type default)
			)
			(layer "F.SilkS")
		)
		(fp_line
			(start -0.7874 0.4064)
			(end -0.7874 -0.4064)
			(stroke
				(width 0.1524)
				(type default)
			)
			(layer "F.SilkS")
		)
		(fp_line
			(start 0.7874 -0.4064)
			(end 0.7874 0.4064)
			(stroke
				(width 0.1524)
				(type default)
			)
			(layer "F.SilkS")
		)
		(fp_line
			(start 0.7874 0.4064)
			(end -0.7874 0.4064)
			(stroke
				(width 0.1524)
				(type default)
			)
			(layer "F.SilkS")
		)
		(fp_line
			(start -0.67945 -0.305054)
			(end -0.12065 -0.305054)
			(stroke
				(width 0.1)
				(type default)
			)
			(layer "F.Fab")
		)
		(fp_line
			(start -0.67945 0.3048)
			(end -0.67945 -0.305054)
			(stroke
				(width 0.1)
				(type default)
			)
			(layer "F.Fab")
		)
		(fp_line
			(start -0.12065 -0.305054)
			(end -0.12065 -0.2794)
			(stroke
				(width 0.1)
				(type default)
			)
			(layer "F.Fab")
		)
		(fp_line
			(start -0.12065 -0.2794)
			(end 0.12065 -0.2794)
			(stroke
				(width 0.1)
				(type default)
			)
			(layer "F.Fab")
		)
		(fp_line
			(start -0.12065 0.2794)
			(end -0.12065 0.3048)
			(stroke
				(width 0.1)
				(type default)
			)
			(layer "F.Fab")
		)
		(fp_line
			(start -0.12065 0.3048)
			(end -0.67945 0.3048)
			(stroke
				(width 0.1)
				(type default)
			)
			(layer "F.Fab")
		)
		(fp_line
			(start 0.120396 0.2794)
			(end -0.12065 0.2794)
			(stroke
				(width 0.1)
				(type default)
			)
			(layer "F.Fab")
		)
		(fp_line
			(start 0.120396 0.3048)
			(end 0.120396 0.2794)
			(stroke
				(width 0.1)
				(type default)
			)
			(layer "F.Fab")
		)
		(fp_line
			(start 0.12065 -0.3048)
			(end 0.67945 -0.3048)
			(stroke
				(width 0.1)
				(type default)
			)
			(layer "F.Fab")
		)
		(fp_line
			(start 0.12065 -0.2794)
			(end 0.12065 -0.3048)
			(stroke
				(width 0.1)
				(type default)
			)
			(layer "F.Fab")
		)
		(fp_line
			(start 0.67945 -0.3048)
			(end 0.67945 0.3048)
			(stroke
				(width 0.1)
				(type default)
			)
			(layer "F.Fab")
		)
		(fp_line
			(start 0.67945 0.3048)
			(end 0.120396 0.3048)
			(stroke
				(width 0.1)
				(type default)
			)
			(layer "F.Fab")
		)
		(pad "1" smd circle
			(at -0.40005 0)
			(size 0 0)
			(layers "F.Cu" "F.Mask" "F.Paste")
			(net "P12V_SSD5_R")
		)
		(pad "2" smd circle
			(at 0.40005 0)
			(size 0 0)
			(layers "F.Cu" "F.Mask" "F.Paste")
			(net "P12V_SSD5_PG_G1")
		)
	)
	(footprint ""
		(layer "F.Cu")
		(at 143.486886 -307.803296 -135)
		(property "Reference" "R1262"
			(at 0 0 225)
			(layer "F.SilkS")
			(hide yes)
			(effects
				(font
					(size 1.27 1.27)
				)
			)
		)
		(property "Value" ""
			(at 0 0 225)
			(layer "F.Fab")
			(effects
				(font
					(size 1.27 1.27)
				)
			)
		)
		(duplicate_pad_numbers_are_jumpers no)
		(fp_line
			(start 0.787389 0.406267)
			(end -0.787389 0.406267)
			(stroke
				(width 0.1524)
				(type default)
			)
			(layer "F.SilkS")
		)
		(fp_line
			(start 0.787389 -0.406267)
			(end 0.787389 0.406267)
			(stroke
				(width 0.1524)
				(type default)
			)
			(layer "F.SilkS")
		)
		(fp_line
			(start -0.787389 0.406267)
			(end -0.787389 -0.406267)
			(stroke
				(width 0.1524)
				(type default)
			)
			(layer "F.SilkS")
		)
		(fp_line
			(start -0.787389 -0.406267)
			(end 0.787389 -0.406267)
			(stroke
				(width 0.1524)
				(type default)
			)
			(layer "F.SilkS")
		)
		(fp_line
			(start 0.679446 0.30479)
			(end 0.120515 0.30479)
			(stroke
				(width 0.1)
				(type default)
			)
			(layer "F.Fab")
		)
		(fp_line
			(start 0.120515 0.30479)
			(end 0.120335 0.279466)
			(stroke
				(width 0.1)
				(type default)
			)
			(layer "F.Fab")
		)
		(fp_line
			(start 0.120335 0.279466)
			(end -0.120695 0.279466)
			(stroke
				(width 0.1)
				(type default)
			)
			(layer "F.Fab")
		)
		(fp_line
			(start 0.679446 -0.30479)
			(end 0.679446 0.30479)
			(stroke
				(width 0.1)
				(type default)
			)
			(layer "F.Fab")
		)
		(fp_line
			(start -0.120515 0.30479)
			(end -0.679446 0.30479)
			(stroke
				(width 0.1)
				(type default)
			)
			(layer "F.Fab")
		)
		(fp_line
			(start -0.120695 0.279466)
			(end -0.120515 0.30479)
			(stroke
				(width 0.1)
				(type default)
			)
			(layer "F.Fab")
		)
		(fp_line
			(start 0.120695 -0.279466)
			(end 0.120515 -0.30479)
			(stroke
				(width 0.1)
				(type default)
			)
			(layer "F.Fab")
		)
		(fp_line
			(start 0.120515 -0.30479)
			(end 0.679446 -0.30479)
			(stroke
				(width 0.1)
				(type default)
			)
			(layer "F.Fab")
		)
		(fp_line
			(start -0.679446 0.30479)
			(end -0.679446 -0.305149)
			(stroke
				(width 0.1)
				(type default)
			)
			(layer "F.Fab")
		)
		(fp_line
			(start -0.120695 -0.279466)
			(end 0.120695 -0.279466)
			(stroke
				(width 0.1)
				(type default)
			)
			(layer "F.Fab")
		)
		(fp_line
			(start -0.120695 -0.304969)
			(end -0.120695 -0.279466)
			(stroke
				(width 0.1)
				(type default)
			)
			(layer "F.Fab")
		)
		(fp_line
			(start -0.679446 -0.305149)
			(end -0.120695 -0.304969)
			(stroke
				(width 0.1)
				(type default)
			)
			(layer "F.Fab")
		)
		(pad "1" smd circle
			(at -0.40005 0 225)
			(size 0 0)
			(layers "F.Cu" "F.Mask" "F.Paste")
			(net "PEX1_DBG_SEL0")
		)
		(pad "2" smd circle
			(at 0.40005 0 225)
			(size 0 0)
			(layers "F.Cu" "F.Mask" "F.Paste")
			(net "P1V8_PEX")
		)
	)
	(footprint ""
		(layer "F.Cu")
		(at 53.126132 -39.73576 -90)
		(property "Reference" "R5545"
			(at 0 0 270)
			(layer "F.SilkS")
			(hide yes)
			(effects
				(font
					(size 1.27 1.27)
				)
			)
		)
		(property "Value" ""
			(at 0 0 270)
			(layer "F.Fab")
			(effects
				(font
					(size 1.27 1.27)
				)
			)
		)
		(duplicate_pad_numbers_are_jumpers no)
		(fp_line
			(start -0.7874 0.4064)
			(end -0.7874 -0.4064)
			(stroke
				(width 0.1524)
				(type default)
			)
			(layer "F.SilkS")
		)
		(fp_line
			(start 0.7874 0.4064)
			(end -0.7874 0.4064)
			(stroke
				(width 0.1524)
				(type default)
			)
			(layer "F.SilkS")
		)
		(fp_line
			(start -0.7874 -0.4064)
			(end 0.7874 -0.4064)
			(stroke
				(width 0.1524)
				(type default)
			)
			(layer "F.SilkS")
		)
		(fp_line
			(start 0.7874 -0.4064)
			(end 0.7874 0.4064)
			(stroke
				(width 0.1524)
				(type default)
			)
			(layer "F.SilkS")
		)
		(fp_line
			(start -0.67945 0.3048)
			(end -0.67945 -0.305054)
			(stroke
				(width 0.1)
				(type default)
			)
			(layer "F.Fab")
		)
		(fp_line
			(start -0.12065 0.3048)
			(end -0.67945 0.3048)
			(stroke
				(width 0.1)
				(type default)
			)
			(layer "F.Fab")
		)
		(fp_line
			(start 0.120396 0.3048)
			(end 0.120396 0.2794)
			(stroke
				(width 0.1)
				(type default)
			)
			(layer "F.Fab")
		)
		(fp_line
			(start 0.67945 0.3048)
			(end 0.120396 0.3048)
			(stroke
				(width 0.1)
				(type default)
			)
			(layer "F.Fab")
		)
		(fp_line
			(start -0.12065 0.2794)
			(end -0.12065 0.3048)
			(stroke
				(width 0.1)
				(type default)
			)
			(layer "F.Fab")
		)
		(fp_line
			(start 0.120396 0.2794)
			(end -0.12065 0.2794)
			(stroke
				(width 0.1)
				(type default)
			)
			(layer "F.Fab")
		)
		(fp_line
			(start -0.12065 -0.2794)
			(end 0.12065 -0.2794)
			(stroke
				(width 0.1)
				(type default)
			)
			(layer "F.Fab")
		)
		(fp_line
			(start 0.12065 -0.2794)
			(end 0.12065 -0.3048)
			(stroke
				(width 0.1)
				(type default)
			)
			(layer "F.Fab")
		)
		(fp_line
			(start 0.12065 -0.3048)
			(end 0.67945 -0.3048)
			(stroke
				(width 0.1)
				(type default)
			)
			(layer "F.Fab")
		)
		(fp_line
			(start 0.67945 -0.3048)
			(end 0.67945 0.3048)
			(stroke
				(width 0.1)
				(type default)
			)
			(layer "F.Fab")
		)
		(fp_line
			(start -0.67945 -0.305054)
			(end -0.12065 -0.305054)
			(stroke
				(width 0.1)
				(type default)
			)
			(layer "F.Fab")
		)
		(fp_line
			(start -0.12065 -0.305054)
			(end -0.12065 -0.2794)
			(stroke
				(width 0.1)
				(type default)
			)
			(layer "F.Fab")
		)
		(pad "1" smd circle
			(at -0.40005 0 270)
			(size 0 0)
			(layers "F.Cu" "F.Mask" "F.Paste")
			(net "P3V3_AUX")
		)
		(pad "2" smd circle
			(at 0.40005 0 270)
			(size 0 0)
			(layers "F.Cu" "F.Mask" "F.Paste")
			(net "SSD2_AUX_P3V3_EN")
		)
	)
	(footprint ""
		(layer "F.Cu")
		(at 419.510972 -350.098614 90)
		(property "Reference" "C817"
			(at 0 0 90)
			(layer "F.SilkS")
			(hide yes)
			(effects
				(font
					(size 1.27 1.27)
				)
			)
		)
		(property "Value" ""
			(at 0 0 90)
			(layer "F.Fab")
			(effects
				(font
					(size 1.27 1.27)
				)
			)
		)
		(duplicate_pad_numbers_are_jumpers no)
		(fp_line
			(start 0.299974 -0.150114)
			(end 0.299974 0.150114)
			(stroke
				(width 0.1)
				(type default)
			)
			(layer "F.Fab")
		)
		(fp_line
			(start -0.299974 -0.150114)
			(end 0.299974 -0.150114)
			(stroke
				(width 0.1)
				(type default)
			)
			(layer "F.Fab")
		)
		(fp_line
			(start 0.299974 0.150114)
			(end -0.299974 0.150114)
			(stroke
				(width 0.1)
				(type default)
			)
			(layer "F.Fab")
		)
		(fp_line
			(start -0.299974 0.150114)
			(end -0.299974 -0.150114)
			(stroke
				(width 0.1)
				(type default)
			)
			(layer "F.Fab")
		)
		(pad "1" smd rect
			(at -0.2667 0 90)
			(size 0.3048 0.381)
			(layers "F.Cu" "F.Mask" "F.Paste")
			(net "P5E_PEX3_STN7_TX_DN<116>")
		)
		(pad "2" smd rect
			(at 0.2667 0 90)
			(size 0.3048 0.381)
			(layers "F.Cu" "F.Mask" "F.Paste")
			(net "P5E_PEX3_STN7_TX_C_DN<116>")
		)
	)
	(footprint ""
		(layer "F.Cu")
		(at 310.443626 -46.90491)
		(property "Reference" "R618"
			(at 0 0 0)
			(layer "F.SilkS")
			(hide yes)
			(effects
				(font
					(size 1.27 1.27)
				)
			)
		)
		(property "Value" ""
			(at 0 0 0)
			(layer "F.Fab")
			(effects
				(font
					(size 1.27 1.27)
				)
			)
		)
		(duplicate_pad_numbers_are_jumpers no)
		(fp_line
			(start -0.7874 -0.4064)
			(end 0.7874 -0.4064)
			(stroke
				(width 0.1524)
				(type default)
			)
			(layer "F.SilkS")
		)
		(fp_line
			(start -0.7874 0.4064)
			(end -0.7874 -0.4064)
			(stroke
				(width 0.1524)
				(type default)
			)
			(layer "F.SilkS")
		)
		(fp_line
			(start 0.7874 -0.4064)
			(end 0.7874 0.4064)
			(stroke
				(width 0.1524)
				(type default)
			)
			(layer "F.SilkS")
		)
		(fp_line
			(start 0.7874 0.4064)
			(end -0.7874 0.4064)
			(stroke
				(width 0.1524)
				(type default)
			)
			(layer "F.SilkS")
		)
		(fp_line
			(start -0.67945 -0.305054)
			(end -0.12065 -0.305054)
			(stroke
				(width 0.1)
				(type default)
			)
			(layer "F.Fab")
		)
		(fp_line
			(start -0.67945 0.3048)
			(end -0.67945 -0.305054)
			(stroke
				(width 0.1)
				(type default)
			)
			(layer "F.Fab")
		)
		(fp_line
			(start -0.12065 -0.305054)
			(end -0.12065 -0.2794)
			(stroke
				(width 0.1)
				(type default)
			)
			(layer "F.Fab")
		)
		(fp_line
			(start -0.12065 -0.2794)
			(end 0.12065 -0.2794)
			(stroke
				(width 0.1)
				(type default)
			)
			(layer "F.Fab")
		)
		(fp_line
			(start -0.12065 0.2794)
			(end -0.12065 0.3048)
			(stroke
				(width 0.1)
				(type default)
			)
			(layer "F.Fab")
		)
		(fp_line
			(start -0.12065 0.3048)
			(end -0.67945 0.3048)
			(stroke
				(width 0.1)
				(type default)
			)
			(layer "F.Fab")
		)
		(fp_line
			(start 0.120396 0.2794)
			(end -0.12065 0.2794)
			(stroke
				(width 0.1)
				(type default)
			)
			(layer "F.Fab")
		)
		(fp_line
			(start 0.120396 0.3048)
			(end 0.120396 0.2794)
			(stroke
				(width 0.1)
				(type default)
			)
			(layer "F.Fab")
		)
		(fp_line
			(start 0.12065 -0.3048)
			(end 0.67945 -0.3048)
			(stroke
				(width 0.1)
				(type default)
			)
			(layer "F.Fab")
		)
		(fp_line
			(start 0.12065 -0.2794)
			(end 0.12065 -0.3048)
			(stroke
				(width 0.1)
				(type default)
			)
			(layer "F.Fab")
		)
		(fp_line
			(start 0.67945 -0.3048)
			(end 0.67945 0.3048)
			(stroke
				(width 0.1)
				(type default)
			)
			(layer "F.Fab")
		)
		(fp_line
			(start 0.67945 0.3048)
			(end 0.120396 0.3048)
			(stroke
				(width 0.1)
				(type default)
			)
			(layer "F.Fab")
		)
		(pad "1" smd circle
			(at -0.40005 0)
			(size 0 0)
			(layers "F.Cu" "F.Mask" "F.Paste")
			(net "SSD10_ADC_ALERT_N")
		)
		(pad "2" smd circle
			(at 0.40005 0)
			(size 0 0)
			(layers "F.Cu" "F.Mask" "F.Paste")
			(net "SSD_8_15_ADC_ALERT_N")
		)
	)
	(footprint ""
		(layer "F.Cu")
		(at 196.119242 -119.584724 180)
		(property "Reference" "C242"
			(at 0 0 180)
			(layer "F.SilkS")
			(hide yes)
			(effects
				(font
					(size 1.27 1.27)
				)
			)
		)
		(property "Value" ""
			(at 0 0 180)
			(layer "F.Fab")
			(effects
				(font
					(size 1.27 1.27)
				)
			)
		)
		(duplicate_pad_numbers_are_jumpers no)
		(fp_line
			(start 0.299974 0.150114)
			(end -0.299974 0.150114)
			(stroke
				(width 0.1)
				(type default)
			)
			(layer "F.Fab")
		)
		(fp_line
			(start 0.299974 -0.150114)
			(end 0.299974 0.150114)
			(stroke
				(width 0.1)
				(type default)
			)
			(layer "F.Fab")
		)
		(fp_line
			(start -0.299974 0.150114)
			(end -0.299974 -0.150114)
			(stroke
				(width 0.1)
				(type default)
			)
			(layer "F.Fab")
		)
		(fp_line
			(start -0.299974 -0.150114)
			(end 0.299974 -0.150114)
			(stroke
				(width 0.1)
				(type default)
			)
			(layer "F.Fab")
		)
		(pad "1" smd rect
			(at -0.2667 0 180)
			(size 0.3048 0.381)
			(layers "F.Cu" "F.Mask" "F.Paste")
			(net "P5E_PEX1_STN0_TX_DP<0>")
		)
		(pad "2" smd rect
			(at 0.2667 0 180)
			(size 0.3048 0.381)
			(layers "F.Cu" "F.Mask" "F.Paste")
			(net "P5E_PEX1_STN0_TX_C_DP<0>")
		)
	)
)
